(kicad_pcb
	(version 20260206)
	(generator "pcbnew")
	(generator_version "10.0")
	(general
		(thickness 1.6)
		(legacy_teardrops no)
	)
	(paper "A4")
	(title_block
		(title "04192023_DAF0TMB3IC0_F0TG_MB_C_brd_V02_OCP.brd")
		(comment 1 "Grand Teton / footprints 859-864 of 8354")
	)
	(layers
		(0 "F.Cu" signal "TOP")
		(4 "In1.Cu" signal "GND")
		(6 "In2.Cu" signal "IN1")
		(8 "In3.Cu" signal "GND1")
		(10 "In4.Cu" signal "IN2")
		(12 "In5.Cu" signal "GND2")
		(14 "In6.Cu" signal "IN3")
		(16 "In7.Cu" signal "GND3")
		(18 "In8.Cu" signal "VCC")
		(20 "In9.Cu" signal "VCC1")
		(22 "In10.Cu" signal "GND4")
		(24 "In11.Cu" signal "IN4")
		(26 "In12.Cu" signal "GND5")
		(28 "In13.Cu" signal "IN5")
		(30 "In14.Cu" signal "GND6")
		(32 "In15.Cu" signal "IN6")
		(34 "In16.Cu" signal "GND7")
		(2 "B.Cu" signal "BOTTOM")
		(9 "F.Adhes" user "F.Adhesive")
		(11 "B.Adhes" user "B.Adhesive")
		(13 "F.Paste" user "Package Geometry/Pastemask Top")
		(15 "B.Paste" user "Package Geometry/Pastemask Bottom")
		(5 "F.SilkS" user "Ref Des/Silkscreen Top")
		(7 "B.SilkS" user "Ref Des/Silkscreen Bottom")
		(1 "F.Mask" user "Board Geometry/Soldermask Top")
		(3 "B.Mask" user "Board Geometry/Soldermask Bottom")
		(17 "Dwgs.User" user "User.Drawings")
		(19 "Cmts.User" user "User.Comments")
		(21 "Eco1.User" user "User.Eco1")
		(23 "Eco2.User" user "User.Eco2")
		(25 "Edge.Cuts" user "Board Geometry/Outline")
		(27 "Margin" user)
		(31 "F.CrtYd" user "Package Geometry/Place Bound Top")
		(29 "B.CrtYd" user "Package Geometry/Place Bound Bottom")
		(35 "F.Fab" user "Ref Des/Assembly Top")
		(33 "B.Fab" user "Ref Des/Assembly Bottom")
	)
	(footprint ""
		(layer "F.Cu")
		(at 176.528984 -147.086574 90)
		(property "Reference" "R493"
			(at 0 0 90)
			(layer "F.SilkS")
			(hide yes)
			(effects
				(font
					(size 1.27 1.27)
				)
			)
		)
		(property "Value" ""
			(at 0 0 90)
			(layer "F.Fab")
			(effects
				(font
					(size 1.27 1.27)
				)
			)
		)
		(duplicate_pad_numbers_are_jumpers no)
		(fp_line
			(start 0.7874 -0.4064)
			(end 0.7874 0.4064)
			(stroke
				(width 0.1524)
				(type default)
			)
			(layer "F.SilkS")
		)
		(fp_line
			(start -0.7874 -0.4064)
			(end 0.7874 -0.4064)
			(stroke
				(width 0.1524)
				(type default)
			)
			(layer "F.SilkS")
		)
		(fp_line
			(start 0.7874 0.4064)
			(end -0.7874 0.4064)
			(stroke
				(width 0.1524)
				(type default)
			)
			(layer "F.SilkS")
		)
		(fp_line
			(start -0.7874 0.4064)
			(end -0.7874 -0.4064)
			(stroke
				(width 0.1524)
				(type default)
			)
			(layer "F.SilkS")
		)
		(fp_line
			(start -0.12065 -0.305054)
			(end -0.12065 -0.2794)
			(stroke
				(width 0.1)
				(type default)
			)
			(layer "F.Fab")
		)
		(fp_line
			(start -0.67945 -0.305054)
			(end -0.12065 -0.305054)
			(stroke
				(width 0.1)
				(type default)
			)
			(layer "F.Fab")
		)
		(fp_line
			(start 0.67945 -0.3048)
			(end 0.67945 0.3048)
			(stroke
				(width 0.1)
				(type default)
			)
			(layer "F.Fab")
		)
		(fp_line
			(start 0.12065 -0.3048)
			(end 0.67945 -0.3048)
			(stroke
				(width 0.1)
				(type default)
			)
			(layer "F.Fab")
		)
		(fp_line
			(start 0.12065 -0.2794)
			(end 0.12065 -0.3048)
			(stroke
				(width 0.1)
				(type default)
			)
			(layer "F.Fab")
		)
		(fp_line
			(start -0.12065 -0.2794)
			(end 0.12065 -0.2794)
			(stroke
				(width 0.1)
				(type default)
			)
			(layer "F.Fab")
		)
		(fp_line
			(start 0.120396 0.2794)
			(end -0.12065 0.2794)
			(stroke
				(width 0.1)
				(type default)
			)
			(layer "F.Fab")
		)
		(fp_line
			(start -0.12065 0.2794)
			(end -0.12065 0.3048)
			(stroke
				(width 0.1)
				(type default)
			)
			(layer "F.Fab")
		)
		(fp_line
			(start 0.67945 0.3048)
			(end 0.120396 0.3048)
			(stroke
				(width 0.1)
				(type default)
			)
			(layer "F.Fab")
		)
		(fp_line
			(start 0.120396 0.3048)
			(end 0.120396 0.2794)
			(stroke
				(width 0.1)
				(type default)
			)
			(layer "F.Fab")
		)
		(fp_line
			(start -0.12065 0.3048)
			(end -0.67945 0.3048)
			(stroke
				(width 0.1)
				(type default)
			)
			(layer "F.Fab")
		)
		(fp_line
			(start -0.67945 0.3048)
			(end -0.67945 -0.305054)
			(stroke
				(width 0.1)
				(type default)
			)
			(layer "F.Fab")
		)
		(pad "1" smd circle
			(at -0.40005 0 90)
			(size 0 0)
			(layers "F.Cu" "F.Mask" "F.Paste")
			(net "SMB_CPU0_4_XLTR_R_SDA")
		)
		(pad "2" smd circle
			(at 0.40005 0 90)
			(size 0 0)
			(layers "F.Cu" "F.Mask" "F.Paste")
			(net "SMB_CPU0_4_XLTR_SDA")
		)
	)
	(footprint ""
		(layer "F.Cu")
		(at 178.71694 -401.452842)
		(property "Reference" "PR3002"
			(at 0 0 0)
			(layer "F.SilkS")
			(hide yes)
			(effects
				(font
					(size 1.27 1.27)
				)
			)
		)
		(property "Value" ""
			(at 0 0 0)
			(layer "F.Fab")
			(effects
				(font
					(size 1.27 1.27)
				)
			)
		)
		(duplicate_pad_numbers_are_jumpers no)
		(fp_line
			(start -0.7874 -0.4064)
			(end 0.7874 -0.4064)
			(stroke
				(width 0.1524)
				(type default)
			)
			(layer "F.SilkS")
		)
		(fp_line
			(start -0.7874 0.4064)
			(end -0.7874 -0.4064)
			(stroke
				(width 0.1524)
				(type default)
			)
			(layer "F.SilkS")
		)
		(fp_line
			(start 0.7874 -0.4064)
			(end 0.7874 0.4064)
			(stroke
				(width 0.1524)
				(type default)
			)
			(layer "F.SilkS")
		)
		(fp_line
			(start 0.7874 0.4064)
			(end -0.7874 0.4064)
			(stroke
				(width 0.1524)
				(type default)
			)
			(layer "F.SilkS")
		)
		(fp_line
			(start -0.67945 -0.305054)
			(end -0.12065 -0.305054)
			(stroke
				(width 0.1)
				(type default)
			)
			(layer "F.Fab")
		)
		(fp_line
			(start -0.67945 0.3048)
			(end -0.67945 -0.305054)
			(stroke
				(width 0.1)
				(type default)
			)
			(layer "F.Fab")
		)
		(fp_line
			(start -0.12065 -0.305054)
			(end -0.12065 -0.2794)
			(stroke
				(width 0.1)
				(type default)
			)
			(layer "F.Fab")
		)
		(fp_line
			(start -0.12065 -0.2794)
			(end 0.12065 -0.2794)
			(stroke
				(width 0.1)
				(type default)
			)
			(layer "F.Fab")
		)
		(fp_line
			(start -0.12065 0.2794)
			(end -0.12065 0.3048)
			(stroke
				(width 0.1)
				(type default)
			)
			(layer "F.Fab")
		)
		(fp_line
			(start -0.12065 0.3048)
			(end -0.67945 0.3048)
			(stroke
				(width 0.1)
				(type default)
			)
			(layer "F.Fab")
		)
		(fp_line
			(start 0.120396 0.2794)
			(end -0.12065 0.2794)
			(stroke
				(width 0.1)
				(type default)
			)
			(layer "F.Fab")
		)
		(fp_line
			(start 0.120396 0.3048)
			(end 0.120396 0.2794)
			(stroke
				(width 0.1)
				(type default)
			)
			(layer "F.Fab")
		)
		(fp_line
			(start 0.12065 -0.3048)
			(end 0.67945 -0.3048)
			(stroke
				(width 0.1)
				(type default)
			)
			(layer "F.Fab")
		)
		(fp_line
			(start 0.12065 -0.2794)
			(end 0.12065 -0.3048)
			(stroke
				(width 0.1)
				(type default)
			)
			(layer "F.Fab")
		)
		(fp_line
			(start 0.67945 -0.3048)
			(end 0.67945 0.3048)
			(stroke
				(width 0.1)
				(type default)
			)
			(layer "F.Fab")
		)
		(fp_line
			(start 0.67945 0.3048)
			(end 0.120396 0.3048)
			(stroke
				(width 0.1)
				(type default)
			)
			(layer "F.Fab")
		)
		(pad "1" smd circle
			(at -0.40005 0)
			(size 0 0)
			(layers "F.Cu" "F.Mask" "F.Paste")
			(net "GND")
		)
		(pad "2" smd circle
			(at 0.40005 0)
			(size 0 0)
			(layers "F.Cu" "F.Mask" "F.Paste")
			(net "AGND_HSC")
		)
	)
	(footprint ""
		(layer "F.Cu")
		(at 29.35986 -351.372932 90)
		(property "Reference" "PR372"
			(at 0 0 90)
			(layer "F.SilkS")
			(hide yes)
			(effects
				(font
					(size 1.27 1.27)
				)
			)
		)
		(property "Value" ""
			(at 0 0 90)
			(layer "F.Fab")
			(effects
				(font
					(size 1.27 1.27)
				)
			)
		)
		(duplicate_pad_numbers_are_jumpers no)
		(fp_line
			(start 0.7874 -0.4064)
			(end 0.7874 0.4064)
			(stroke
				(width 0.1524)
				(type default)
			)
			(layer "F.SilkS")
		)
		(fp_line
			(start -0.7874 -0.4064)
			(end 0.7874 -0.4064)
			(stroke
				(width 0.1524)
				(type default)
			)
			(layer "F.SilkS")
		)
		(fp_line
			(start 0.7874 0.4064)
			(end -0.7874 0.4064)
			(stroke
				(width 0.1524)
				(type default)
			)
			(layer "F.SilkS")
		)
		(fp_line
			(start -0.7874 0.4064)
			(end -0.7874 -0.4064)
			(stroke
				(width 0.1524)
				(type default)
			)
			(layer "F.SilkS")
		)
		(fp_line
			(start -0.12065 -0.305054)
			(end -0.12065 -0.2794)
			(stroke
				(width 0.1)
				(type default)
			)
			(layer "F.Fab")
		)
		(fp_line
			(start -0.67945 -0.305054)
			(end -0.12065 -0.305054)
			(stroke
				(width 0.1)
				(type default)
			)
			(layer "F.Fab")
		)
		(fp_line
			(start 0.67945 -0.3048)
			(end 0.67945 0.3048)
			(stroke
				(width 0.1)
				(type default)
			)
			(layer "F.Fab")
		)
		(fp_line
			(start 0.12065 -0.3048)
			(end 0.67945 -0.3048)
			(stroke
				(width 0.1)
				(type default)
			)
			(layer "F.Fab")
		)
		(fp_line
			(start 0.12065 -0.2794)
			(end 0.12065 -0.3048)
			(stroke
				(width 0.1)
				(type default)
			)
			(layer "F.Fab")
		)
		(fp_line
			(start -0.12065 -0.2794)
			(end 0.12065 -0.2794)
			(stroke
				(width 0.1)
				(type default)
			)
			(layer "F.Fab")
		)
		(fp_line
			(start 0.120396 0.2794)
			(end -0.12065 0.2794)
			(stroke
				(width 0.1)
				(type default)
			)
			(layer "F.Fab")
		)
		(fp_line
			(start -0.12065 0.2794)
			(end -0.12065 0.3048)
			(stroke
				(width 0.1)
				(type default)
			)
			(layer "F.Fab")
		)
		(fp_line
			(start 0.67945 0.3048)
			(end 0.120396 0.3048)
			(stroke
				(width 0.1)
				(type default)
			)
			(layer "F.Fab")
		)
		(fp_line
			(start 0.120396 0.3048)
			(end 0.120396 0.2794)
			(stroke
				(width 0.1)
				(type default)
			)
			(layer "F.Fab")
		)
		(fp_line
			(start -0.12065 0.3048)
			(end -0.67945 0.3048)
			(stroke
				(width 0.1)
				(type default)
			)
			(layer "F.Fab")
		)
		(fp_line
			(start -0.67945 0.3048)
			(end -0.67945 -0.305054)
			(stroke
				(width 0.1)
				(type default)
			)
			(layer "F.Fab")
		)
		(pad "1" smd circle
			(at -0.40005 0 90)
			(size 0 0)
			(layers "F.Cu" "F.Mask" "F.Paste")
			(net "SW_PVDDIO_P1_BOOT4")
		)
		(pad "2" smd circle
			(at 0.40005 0 90)
			(size 0 0)
			(layers "F.Cu" "F.Mask" "F.Paste")
			(net "SW_PVDDIO_P1_BOOT4_R")
		)
	)
	(footprint ""
		(layer "F.Cu")
		(at 109.095794 -385.48056)
		(property "Reference" "R915"
			(at 0 0 0)
			(layer "F.SilkS")
			(hide yes)
			(effects
				(font
					(size 1.27 1.27)
				)
			)
		)
		(property "Value" ""
			(at 0 0 0)
			(layer "F.Fab")
			(effects
				(font
					(size 1.27 1.27)
				)
			)
		)
		(duplicate_pad_numbers_are_jumpers no)
		(fp_line
			(start -0.32512 -0.175006)
			(end 0.32512 -0.175006)
			(stroke
				(width 0.1)
				(type default)
			)
			(layer "F.Fab")
		)
		(fp_line
			(start -0.32512 0.175006)
			(end -0.32512 -0.175006)
			(stroke
				(width 0.1)
				(type default)
			)
			(layer "F.Fab")
		)
		(fp_line
			(start 0.32512 -0.175006)
			(end 0.32512 0.175006)
			(stroke
				(width 0.1)
				(type default)
			)
			(layer "F.Fab")
		)
		(fp_line
			(start 0.32512 0.175006)
			(end -0.32512 0.175006)
			(stroke
				(width 0.1)
				(type default)
			)
			(layer "F.Fab")
		)
		(pad "1" smd rect
			(at -0.2667 0)
			(size 0.3048 0.381)
			(layers "F.Cu" "F.Mask" "F.Paste")
			(net "P1V8_CPU1_RT_1D")
		)
		(pad "2" smd rect
			(at 0.2667 0 180)
			(size 0.3048 0.381)
			(layers "F.Cu" "F.Mask" "F.Paste")
			(net "GPIO2_RT_CPU1_P3")
		)
	)
	(footprint ""
		(layer "F.Cu")
		(at 112.597946 -52.86248 -90)
		(property "Reference" "R6299"
			(at 0 0 270)
			(layer "F.SilkS")
			(hide yes)
			(effects
				(font
					(size 1.27 1.27)
				)
			)
		)
		(property "Value" ""
			(at 0 0 270)
			(layer "F.Fab")
			(effects
				(font
					(size 1.27 1.27)
				)
			)
		)
		(duplicate_pad_numbers_are_jumpers no)
		(fp_line
			(start -0.7874 0.4064)
			(end -0.7874 -0.4064)
			(stroke
				(width 0.1524)
				(type default)
			)
			(layer "F.SilkS")
		)
		(fp_line
			(start 0.7874 0.4064)
			(end -0.7874 0.4064)
			(stroke
				(width 0.1524)
				(type default)
			)
			(layer "F.SilkS")
		)
		(fp_line
			(start -0.7874 -0.4064)
			(end 0.7874 -0.4064)
			(stroke
				(width 0.1524)
				(type default)
			)
			(layer "F.SilkS")
		)
		(fp_line
			(start 0.7874 -0.4064)
			(end 0.7874 0.4064)
			(stroke
				(width 0.1524)
				(type default)
			)
			(layer "F.SilkS")
		)
		(fp_line
			(start -0.67945 0.3048)
			(end -0.67945 -0.305054)
			(stroke
				(width 0.1)
				(type default)
			)
			(layer "F.Fab")
		)
		(fp_line
			(start -0.12065 0.3048)
			(end -0.67945 0.3048)
			(stroke
				(width 0.1)
				(type default)
			)
			(layer "F.Fab")
		)
		(fp_line
			(start 0.120396 0.3048)
			(end 0.120396 0.2794)
			(stroke
				(width 0.1)
				(type default)
			)
			(layer "F.Fab")
		)
		(fp_line
			(start 0.67945 0.3048)
			(end 0.120396 0.3048)
			(stroke
				(width 0.1)
				(type default)
			)
			(layer "F.Fab")
		)
		(fp_line
			(start -0.12065 0.2794)
			(end -0.12065 0.3048)
			(stroke
				(width 0.1)
				(type default)
			)
			(layer "F.Fab")
		)
		(fp_line
			(start 0.120396 0.2794)
			(end -0.12065 0.2794)
			(stroke
				(width 0.1)
				(type default)
			)
			(layer "F.Fab")
		)
		(fp_line
			(start -0.12065 -0.2794)
			(end 0.12065 -0.2794)
			(stroke
				(width 0.1)
				(type default)
			)
			(layer "F.Fab")
		)
		(fp_line
			(start 0.12065 -0.2794)
			(end 0.12065 -0.3048)
			(stroke
				(width 0.1)
				(type default)
			)
			(layer "F.Fab")
		)
		(fp_line
			(start 0.12065 -0.3048)
			(end 0.67945 -0.3048)
			(stroke
				(width 0.1)
				(type default)
			)
			(layer "F.Fab")
		)
		(fp_line
			(start 0.67945 -0.3048)
			(end 0.67945 0.3048)
			(stroke
				(width 0.1)
				(type default)
			)
			(layer "F.Fab")
		)
		(fp_line
			(start -0.67945 -0.305054)
			(end -0.12065 -0.305054)
			(stroke
				(width 0.1)
				(type default)
			)
			(layer "F.Fab")
		)
		(fp_line
			(start -0.12065 -0.305054)
			(end -0.12065 -0.2794)
			(stroke
				(width 0.1)
				(type default)
			)
			(layer "F.Fab")
		)
		(pad "1" smd circle
			(at -0.40005 0 270)
			(size 0 0)
			(layers "F.Cu" "F.Mask" "F.Paste")
			(net "USB_HUB2_TI_OVERCUR3")
		)
		(pad "2" smd circle
			(at 0.40005 0 270)
			(size 0 0)
			(layers "F.Cu" "F.Mask" "F.Paste")
			(net "USB_HUB2_TI_OVERCUR3_MRP_CFG_BC_EN")
		)
	)
	(footprint ""
		(layer "F.Cu")
		(at 353.38004 -44.250102 -90)
		(property "Reference" "J212"
			(at -3.273298 4.965192 0)
			(unlocked yes)
			(layer "F.SilkS")
			(effects
				(font
					(size 0.7874 0.5842)
					(thickness 0.1524)
				)
				(justify left)
			)
		)
		(property "Value" ""
			(at 0 0 270)
			(layer "F.Fab")
			(effects
				(font
					(size 1.27 1.27)
				)
			)
		)
		(duplicate_pad_numbers_are_jumpers no)
		(fp_line
			(start -1.219962 11.495024)
			(end 3.759962 11.495024)
			(stroke
				(width 0.1524)
				(type default)
			)
			(layer "F.SilkS")
		)
		(fp_line
			(start 3.759962 11.495024)
			(end 3.759962 -1.335024)
			(stroke
				(width 0.1524)
				(type default)
			)
			(layer "F.SilkS")
		)
		(fp_line
			(start -1.219962 -1.335024)
			(end -1.219962 11.495024)
			(stroke
				(width 0.1524)
				(type default)
			)
			(layer "F.SilkS")
		)
		(fp_line
			(start 3.759962 -1.335024)
			(end -1.219962 -1.335024)
			(stroke
				(width 0.1524)
				(type default)
			)
			(layer "F.SilkS")
		)
		(fp_poly
			(pts
				(xy -2.5146 -0.508) (xy -2.5146 0.508) (xy -1.4986 0)
			)
			(stroke
				(width 0)
				(type default)
			)
			(fill yes)
			(layer "F.SilkS")
		)
		(fp_line
			(start -1.219962 11.495024)
			(end 3.759962 11.495024)
			(stroke
				(width 0.1)
				(type default)
			)
			(layer "F.Fab")
		)
		(fp_line
			(start 3.759962 11.495024)
			(end 3.759962 -1.335024)
			(stroke
				(width 0.1)
				(type default)
			)
			(layer "F.Fab")
		)
		(fp_line
			(start -1.219962 -1.335024)
			(end -1.219962 11.495024)
			(stroke
				(width 0.1)
				(type default)
			)
			(layer "F.Fab")
		)
		(fp_line
			(start 3.759962 -1.335024)
			(end -1.219962 -1.335024)
			(stroke
				(width 0.1)
				(type default)
			)
			(layer "F.Fab")
		)
		(fp_poly
			(pts
				(xy -2.5146 -0.508) (xy -2.5146 0.508) (xy -1.4986 0)
			)
			(stroke
				(width 0)
				(type default)
			)
			(fill yes)
			(layer "F.Fab")
		)
		(pad "1" thru_hole rect
			(at 0 0 270)
			(size 1.6256 1.6256)
			(drill 1.1176)
			(layers "*.Cu" "*.Mask")
			(remove_unused_layers no)
			(net "CPU0_XTRIG_L4")
			(clearance 0)
			(padstack
				(mode front_inner_back)
				(layer "Inner"
					(shape circle)
					(size 1.6256 1.6256)
					(clearance 0)
				)
				(layer "B.Cu"
					(shape rect)
					(size 1.6256 1.6256)
					(clearance 0)
				)
			)
		)
		(pad "2" thru_hole circle
			(at 2.54 0 270)
			(size 1.6256 1.6256)
			(drill 1.1176)
			(layers "*.Cu" "*.Mask")
			(remove_unused_layers no)
			(net "CPU1_XTRIG_L4")
			(clearance 0)
		)
		(pad "3" thru_hole circle
			(at 0 2.54 270)
			(size 1.6256 1.6256)
			(drill 1.1176)
			(layers "*.Cu" "*.Mask")
			(remove_unused_layers no)
			(net "CPU0_XTRIG_L5")
			(clearance 0)
		)
		(pad "4" thru_hole circle
			(at 2.54 2.54 270)
			(size 1.6256 1.6256)
			(drill 1.1176)
			(layers "*.Cu" "*.Mask")
			(remove_unused_layers no)
			(net "CPU1_XTRIG_L5")
			(clearance 0)
		)
		(pad "5" thru_hole circle
			(at 0 5.08 270)
			(size 1.6256 1.6256)
			(drill 1.1176)
			(layers "*.Cu" "*.Mask")
			(remove_unused_layers no)
			(net "CPU0_XTRIG_L6")
			(clearance 0)
		)
		(pad "6" thru_hole circle
			(at 2.54 5.08 270)
			(size 1.6256 1.6256)
			(drill 1.1176)
			(layers "*.Cu" "*.Mask")
			(remove_unused_layers no)
			(net "CPU1_XTRIG_L6")
			(clearance 0)
		)
		(pad "7" thru_hole circle
			(at 0 7.62 270)
			(size 1.6256 1.6256)
			(drill 1.1176)
			(layers "*.Cu" "*.Mask")
			(remove_unused_layers no)
			(net "CPU0_XTRIG_L7")
			(clearance 0)
		)
		(pad "8" thru_hole circle
			(at 2.54 7.62 270)
			(size 1.6256 1.6256)
			(drill 1.1176)
			(layers "*.Cu" "*.Mask")
			(remove_unused_layers no)
			(net "CPU1_XTRIG_L7")
			(clearance 0)
		)
		(pad "9" thru_hole circle
			(at 0 10.16 270)
			(size 1.6256 1.6256)
			(drill 1.1176)
			(layers "*.Cu" "*.Mask")
			(remove_unused_layers no)
			(net "Net_1766")
			(clearance 0)
		)
		(pad "10" thru_hole circle
			(at 2.54 10.16 270)
			(size 1.6256 1.6256)
			(drill 1.1176)
			(layers "*.Cu" "*.Mask")
			(remove_unused_layers no)
			(net "Net_1765")
			(clearance 0)
		)
	)
)
